(kicad_pcb
	(version 20260206)
	(generator "pcbnew")
	(generator_version "10.0")
	(general
		(thickness 1.6)
		(legacy_teardrops no)
	)
	(paper "A4")
	(title_block
		(title "pdpb — Lightning_PDPB_BRD.brd")
		(comment 1 "Lightning (Wiwynn / Facebook NVMe JBOF) / footprints 115-121 of 1140")
	)
	(layers
		(0 "F.Cu" signal "TOP")
		(4 "In1.Cu" signal "L2GND")
		(6 "In2.Cu" signal "L3")
		(8 "In3.Cu" signal "L4VCC")
		(10 "In4.Cu" signal "L5VCC")
		(12 "In5.Cu" signal "L6")
		(14 "In6.Cu" signal "L7GND")
		(2 "B.Cu" signal "BOTTOM")
		(9 "F.Adhes" user "F.Adhesive")
		(11 "B.Adhes" user "B.Adhesive")
		(13 "F.Paste" user "Package Geometry/Pastemask Top")
		(15 "B.Paste" user "Package Geometry/Pastemask Bottom")
		(5 "F.SilkS" user "Ref Des/Silkscreen Top")
		(7 "B.SilkS" user "Ref Des/Silkscreen Bottom")
		(1 "F.Mask" user "Board Geometry/Soldermask Top")
		(3 "B.Mask" user "Board Geometry/Soldermask Bottom")
		(17 "Dwgs.User" user "User.Drawings")
		(19 "Cmts.User" user "User.Comments")
		(21 "Eco1.User" user "User.Eco1")
		(23 "Eco2.User" user "User.Eco2")
		(25 "Edge.Cuts" user "Board Geometry/Outline")
		(27 "Margin" user)
		(31 "F.CrtYd" user "Package Geometry/Place Bound Top")
		(29 "B.CrtYd" user "Package Geometry/Place Bound Bottom")
		(35 "F.Fab" user "Ref Des/Assembly Top")
		(33 "B.Fab" user "Ref Des/Assembly Bottom")
	)
	(footprint ""
		(layer "F.Cu")
		(at 32.131 -81.534 -90)
		(property "Reference" "R405"
			(at 0 0 270)
			(layer "F.SilkS")
			(hide yes)
			(effects
				(font
					(size 1.27 1.27)
				)
			)
		)
		(property "Value" "0R2J-2-GP"
			(at 0.064008 -3.993896 270)
			(unlocked yes)
			(layer "F.Fab")
			(hide yes)
			(effects
				(font
					(size 1.016 1.016)
					(thickness 0.1524)
				)
			)
		)
		(property "Device Type" "R402H16"
			(at 0.064008 -5.517896 270)
			(unlocked yes)
			(layer "F.Fab")
			(hide yes)
			(effects
				(font
					(size 1.016 1.016)
					(thickness 0.1524)
				)
			)
		)
		(duplicate_pad_numbers_are_jumpers no)
		(fp_line
			(start -0.508 -0.9398)
			(end -0.508 0.9398)
			(stroke
				(width 0.1524)
				(type default)
			)
			(layer "F.SilkS")
		)
		(fp_line
			(start 0.508 -0.9398)
			(end -0.508 -0.9398)
			(stroke
				(width 0.1524)
				(type default)
			)
			(layer "F.SilkS")
		)
		(fp_rect
			(start -0.508 0.9398)
			(end 0.508 -0.9398)
			(stroke
				(width 0)
				(type default)
			)
			(fill no)
			(layer "F.CrtYd")
		)
		(fp_rect
			(start -0.508 0.9398)
			(end 0.508 -0.9398)
			(stroke
				(width 0)
				(type default)
			)
			(fill no)
			(layer "F.Fab")
		)
		(pad "1" smd custom
			(at 0 -0.4445 270)
			(size 0.1397 0.1397)
			(layers "F.Cu" "F.Mask" "F.Paste")
			(net "SCL_DR9_R")
			(options
				(clearance outline)
				(anchor circle)
			)
			(primitives
				(gr_poly
					(pts
						(arc
							(start -0.1778 -0.2794)
							(mid -0.249642 -0.249642)
							(end -0.2794 -0.1778)
						)
						(arc
							(start -0.2794 0.1778)
							(mid -0.249642 0.249642)
							(end -0.1778 0.2794)
						)
						(arc
							(start 0.1778 0.2794)
							(mid 0.249642 0.249642)
							(end 0.2794 0.1778)
						)
						(arc
							(start 0.2794 -0.1778)
							(mid 0.249642 -0.249642)
							(end 0.1778 -0.2794)
						)
					)
					(width 0)
					(fill yes)
				)
			)
		)
		(pad "2" smd custom
			(at 0 0.4445 270)
			(size 0.1397 0.1397)
			(layers "F.Cu" "F.Mask" "F.Paste")
			(net "SCL_DR9")
			(options
				(clearance outline)
				(anchor circle)
			)
			(primitives
				(gr_poly
					(pts
						(arc
							(start -0.1778 -0.2794)
							(mid -0.249642 -0.249642)
							(end -0.2794 -0.1778)
						)
						(arc
							(start -0.2794 0.1778)
							(mid -0.249642 0.249642)
							(end -0.1778 0.2794)
						)
						(arc
							(start 0.1778 0.2794)
							(mid 0.249642 0.249642)
							(end 0.2794 0.1778)
						)
						(arc
							(start 0.2794 -0.1778)
							(mid 0.249642 -0.249642)
							(end 0.1778 -0.2794)
						)
					)
					(width 0)
					(fill yes)
				)
			)
		)
	)
	(footprint ""
		(layer "F.Cu")
		(at 217.043 -184.531 -90)
		(property "Reference" "R393"
			(at 0 0 270)
			(layer "F.SilkS")
			(hide yes)
			(effects
				(font
					(size 1.27 1.27)
				)
			)
		)
		(property "Value" "0R2J-2-GP"
			(at 0.064008 -3.993896 270)
			(unlocked yes)
			(layer "F.Fab")
			(hide yes)
			(effects
				(font
					(size 1.016 1.016)
					(thickness 0.1524)
				)
			)
		)
		(property "Device Type" "R402H16"
			(at 0.064008 -5.517896 270)
			(unlocked yes)
			(layer "F.Fab")
			(hide yes)
			(effects
				(font
					(size 1.016 1.016)
					(thickness 0.1524)
				)
			)
		)
		(duplicate_pad_numbers_are_jumpers no)
		(fp_line
			(start -0.508 -0.9398)
			(end -0.508 0.9398)
			(stroke
				(width 0.1524)
				(type default)
			)
			(layer "F.SilkS")
		)
		(fp_line
			(start 0.508 -0.9398)
			(end -0.508 -0.9398)
			(stroke
				(width 0.1524)
				(type default)
			)
			(layer "F.SilkS")
		)
		(fp_rect
			(start -0.508 0.9398)
			(end 0.508 -0.9398)
			(stroke
				(width 0)
				(type default)
			)
			(fill no)
			(layer "F.CrtYd")
		)
		(fp_rect
			(start -0.508 0.9398)
			(end 0.508 -0.9398)
			(stroke
				(width 0)
				(type default)
			)
			(fill no)
			(layer "F.Fab")
		)
		(pad "1" smd custom
			(at 0 -0.4445 270)
			(size 0.1397 0.1397)
			(layers "F.Cu" "F.Mask" "F.Paste")
			(net "SCL_DR3_R")
			(options
				(clearance outline)
				(anchor circle)
			)
			(primitives
				(gr_poly
					(pts
						(arc
							(start -0.1778 -0.2794)
							(mid -0.249642 -0.249642)
							(end -0.2794 -0.1778)
						)
						(arc
							(start -0.2794 0.1778)
							(mid -0.249642 0.249642)
							(end -0.1778 0.2794)
						)
						(arc
							(start 0.1778 0.2794)
							(mid 0.249642 0.249642)
							(end 0.2794 0.1778)
						)
						(arc
							(start 0.2794 -0.1778)
							(mid 0.249642 -0.249642)
							(end 0.1778 -0.2794)
						)
					)
					(width 0)
					(fill yes)
				)
			)
		)
		(pad "2" smd custom
			(at 0 0.4445 270)
			(size 0.1397 0.1397)
			(layers "F.Cu" "F.Mask" "F.Paste")
			(net "SCL_DR3")
			(options
				(clearance outline)
				(anchor circle)
			)
			(primitives
				(gr_poly
					(pts
						(arc
							(start -0.1778 -0.2794)
							(mid -0.249642 -0.249642)
							(end -0.2794 -0.1778)
						)
						(arc
							(start -0.2794 0.1778)
							(mid -0.249642 0.249642)
							(end -0.1778 0.2794)
						)
						(arc
							(start 0.1778 0.2794)
							(mid 0.249642 0.249642)
							(end 0.2794 0.1778)
						)
						(arc
							(start 0.2794 -0.1778)
							(mid 0.249642 -0.249642)
							(end 0.1778 -0.2794)
						)
					)
					(width 0)
					(fill yes)
				)
			)
		)
	)
	(footprint ""
		(layer "F.Cu")
		(at 29.7688 -191.897 -90)
		(property "Reference" "U17"
			(at 0 0 270)
			(layer "F.SilkS")
			(hide yes)
			(effects
				(font
					(size 1.27 1.27)
				)
			)
		)
		(property "Value" "P2003EVG-GP"
			(at 0 -11.1252 270)
			(unlocked yes)
			(layer "F.Fab")
			(hide yes)
			(effects
				(font
					(size 1.016 1.016)
					(thickness 0.1524)
				)
			)
		)
		(property "Device Type" "SOIC8H79"
			(at 0 -12.6492 270)
			(unlocked yes)
			(layer "F.Fab")
			(hide yes)
			(effects
				(font
					(size 1.016 1.016)
					(thickness 0.1524)
				)
			)
		)
		(duplicate_pad_numbers_are_jumpers no)
		(fp_line
			(start -2.6162 3.429)
			(end -2.6162 1.4732)
			(stroke
				(width 0.4064)
				(type default)
			)
			(layer "F.SilkS")
		)
		(fp_line
			(start -2.7432 1.4224)
			(end 2.1336 1.4224)
			(stroke
				(width 0.1524)
				(type default)
			)
			(layer "F.SilkS")
		)
		(fp_line
			(start 2.1336 1.4224)
			(end 2.1336 -1.4224)
			(stroke
				(width 0.1524)
				(type default)
			)
			(layer "F.SilkS")
		)
		(fp_line
			(start -2.2352 0)
			(end -2.7432 0.508)
			(stroke
				(width 0.1524)
				(type default)
			)
			(layer "F.SilkS")
		)
		(fp_line
			(start -2.7432 -0.508)
			(end -2.2352 0)
			(stroke
				(width 0.1524)
				(type default)
			)
			(layer "F.SilkS")
		)
		(fp_line
			(start -2.7432 -1.4224)
			(end -2.7432 1.4224)
			(stroke
				(width 0.1524)
				(type default)
			)
			(layer "F.SilkS")
		)
		(fp_line
			(start 2.1336 -1.4224)
			(end -2.7432 -1.4224)
			(stroke
				(width 0.1524)
				(type default)
			)
			(layer "F.SilkS")
		)
		(fp_poly
			(pts
				(xy 2.2098 -1.4224) (xy 2.2098 1.4224) (xy -2.2225 1.4224) (xy -2.2225 -1.4224)
			)
			(stroke
				(width 0)
				(type default)
			)
			(fill yes)
			(layer "F.SilkS")
		)
		(fp_rect
			(start -2.4511 2.9972)
			(end 2.4511 -2.9972)
			(stroke
				(width 0)
				(type default)
			)
			(fill no)
			(layer "F.CrtYd")
		)
		(fp_poly
			(pts
				(xy -2.8194 3.6322) (xy -2.8194 -3.6322) (xy 2.8194 -3.6322) (xy 2.8194 -2.2987) (xy 2.4511 -2.2987)
				(xy 2.4511 -2.9972) (xy -2.4511 -2.9972) (xy -2.4511 2.9972) (xy 2.4511 2.9972) (xy 2.4511 -2.286)
				(xy 2.8194 -2.286) (xy 2.8194 3.6322)
			)
			(stroke
				(width 0)
				(type default)
			)
			(fill no)
			(layer "F.CrtYd")
		)
		(fp_rect
			(start -2.8194 3.6322)
			(end 2.8194 -3.6322)
			(stroke
				(width 0)
				(type default)
			)
			(fill no)
			(layer "F.Fab")
		)
		(pad "1" smd rect
			(at -1.905 2.54 270)
			(size 0.635 1.651)
			(layers "F.Cu" "F.Mask" "F.Paste")
			(net "P12V")
		)
		(pad "2" smd rect
			(at -0.635 2.54 270)
			(size 0.635 1.651)
			(layers "F.Cu" "F.Mask" "F.Paste")
			(net "P12V")
		)
		(pad "3" smd rect
			(at 0.635 2.54 270)
			(size 0.635 1.651)
			(layers "F.Cu" "F.Mask" "F.Paste")
			(net "P12V")
		)
		(pad "4" smd rect
			(at 1.905 2.54 270)
			(size 0.635 1.651)
			(layers "F.Cu" "F.Mask" "F.Paste")
			(net "SW_SSD8_N")
		)
		(pad "5" smd rect
			(at 1.905 -2.54 270)
			(size 0.635 1.651)
			(layers "F.Cu" "F.Mask" "F.Paste")
			(net "P12V_SSD8")
		)
		(pad "6" smd rect
			(at 0.635 -2.54 270)
			(size 0.635 1.651)
			(layers "F.Cu" "F.Mask" "F.Paste")
			(net "P12V_SSD8")
		)
		(pad "7" smd rect
			(at -0.635 -2.54 270)
			(size 0.635 1.651)
			(layers "F.Cu" "F.Mask" "F.Paste")
			(net "P12V_SSD8")
		)
		(pad "8" smd rect
			(at -1.905 -2.54 270)
			(size 0.635 1.651)
			(layers "F.Cu" "F.Mask" "F.Paste")
			(net "P12V_SSD8")
		)
	)
	(footprint ""
		(layer "F.Cu")
		(at 90.932 -19.304 90)
		(property "Reference" "TP150"
			(at 0 0 90)
			(layer "F.SilkS")
			(hide yes)
			(effects
				(font
					(size 1.27 1.27)
				)
			)
		)
		(property "Value" "TPAD32-GP"
			(at -0.0508 -1.6764 90)
			(unlocked yes)
			(layer "F.Fab")
			(hide yes)
			(effects
				(font
					(size 1.016 1.016)
					(thickness 0.1524)
				)
			)
		)
		(property "Device Type" "TPAD32"
			(at -0.0508 -3.2004 90)
			(unlocked yes)
			(layer "F.Fab")
			(hide yes)
			(effects
				(font
					(size 1.016 1.016)
					(thickness 0.1524)
				)
			)
		)
		(duplicate_pad_numbers_are_jumpers no)
		(fp_poly
			(pts
				(arc
					(start 0 0.4064)
					(mid 0 -0.4064)
					(end 0 0.4064)
				)
			)
			(stroke
				(width 0)
				(type default)
			)
			(fill no)
			(layer "F.CrtYd")
		)
		(fp_poly
			(pts
				(arc
					(start 0 0.7112)
					(mid 0 -0.7112)
					(end 0 0.7112)
				)
			)
			(stroke
				(width 0)
				(type default)
			)
			(fill no)
			(layer "F.Fab")
		)
		(pad "1" smd circle
			(at 0 0 90)
			(size 0.8128 0.8128)
			(layers "F.Cu" "F.Mask" "F.Paste")
			(net "VOL_SEN_ALERT")
		)
	)
	(footprint ""
		(layer "F.Cu")
		(at 15.204186 -52.494434)
		(property "Reference" "R9956"
			(at 0 0 0)
			(layer "F.SilkS")
			(hide yes)
			(effects
				(font
					(size 1.27 1.27)
				)
			)
		)
		(property "Value" "4K7R2J-2-GP"
			(at 0.064008 -3.993896 0)
			(unlocked yes)
			(layer "F.Fab")
			(hide yes)
			(effects
				(font
					(size 1.016 1.016)
					(thickness 0.1524)
				)
			)
		)
		(property "Device Type" "R402H16"
			(at 0.064008 -5.517896 0)
			(unlocked yes)
			(layer "F.Fab")
			(hide yes)
			(effects
				(font
					(size 1.016 1.016)
					(thickness 0.1524)
				)
			)
		)
		(duplicate_pad_numbers_are_jumpers no)
		(fp_line
			(start -0.508 -0.9398)
			(end -0.508 0.9398)
			(stroke
				(width 0.1524)
				(type default)
			)
			(layer "F.SilkS")
		)
		(fp_line
			(start 0.508 -0.9398)
			(end -0.508 -0.9398)
			(stroke
				(width 0.1524)
				(type default)
			)
			(layer "F.SilkS")
		)
		(fp_rect
			(start -0.508 0.9398)
			(end 0.508 -0.9398)
			(stroke
				(width 0)
				(type default)
			)
			(fill no)
			(layer "F.CrtYd")
		)
		(fp_rect
			(start -0.508 0.9398)
			(end 0.508 -0.9398)
			(stroke
				(width 0)
				(type default)
			)
			(fill no)
			(layer "F.Fab")
		)
		(pad "1" smd custom
			(at 0 -0.4445)
			(size 0.1397 0.1397)
			(layers "F.Cu" "F.Mask" "F.Paste")
			(net "P3V3")
			(options
				(clearance outline)
				(anchor circle)
			)
			(primitives
				(gr_poly
					(pts
						(arc
							(start -0.1778 -0.2794)
							(mid -0.249642 -0.249642)
							(end -0.2794 -0.1778)
						)
						(arc
							(start -0.2794 0.1778)
							(mid -0.249642 0.249642)
							(end -0.1778 0.2794)
						)
						(arc
							(start 0.1778 0.2794)
							(mid 0.249642 0.249642)
							(end 0.2794 0.1778)
						)
						(arc
							(start 0.2794 -0.1778)
							(mid 0.249642 -0.249642)
							(end 0.1778 -0.2794)
						)
					)
					(width 0)
					(fill yes)
				)
			)
		)
		(pad "2" smd custom
			(at 0 0.4445)
			(size 0.1397 0.1397)
			(layers "F.Cu" "F.Mask" "F.Paste")
			(net "SSD_ACT_DR14_MOS_N")
			(options
				(clearance outline)
				(anchor circle)
			)
			(primitives
				(gr_poly
					(pts
						(arc
							(start -0.1778 -0.2794)
							(mid -0.249642 -0.249642)
							(end -0.2794 -0.1778)
						)
						(arc
							(start -0.2794 0.1778)
							(mid -0.249642 0.249642)
							(end -0.1778 0.2794)
						)
						(arc
							(start 0.1778 0.2794)
							(mid 0.249642 0.249642)
							(end 0.2794 0.1778)
						)
						(arc
							(start 0.2794 -0.1778)
							(mid 0.249642 -0.249642)
							(end 0.1778 -0.2794)
						)
					)
					(width 0)
					(fill yes)
				)
			)
		)
	)
	(footprint ""
		(layer "F.Cu")
		(at 86.487 -440.436 180)
		(property "Reference" "R9064"
			(at 0 0 180)
			(layer "F.SilkS")
			(hide yes)
			(effects
				(font
					(size 1.27 1.27)
				)
			)
		)
		(property "Value" "27R2F-GP"
			(at 0.064008 -3.993896 180)
			(unlocked yes)
			(layer "F.Fab")
			(hide yes)
			(effects
				(font
					(size 1.016 1.016)
					(thickness 0.1524)
				)
			)
		)
		(property "Device Type" "R402H16"
			(at 0.064008 -5.517896 180)
			(unlocked yes)
			(layer "F.Fab")
			(hide yes)
			(effects
				(font
					(size 1.016 1.016)
					(thickness 0.1524)
				)
			)
		)
		(duplicate_pad_numbers_are_jumpers no)
		(fp_line
			(start 0.508 -0.9398)
			(end -0.508 -0.9398)
			(stroke
				(width 0.1524)
				(type default)
			)
			(layer "F.SilkS")
		)
		(fp_line
			(start -0.508 -0.9398)
			(end -0.508 0.9398)
			(stroke
				(width 0.1524)
				(type default)
			)
			(layer "F.SilkS")
		)
		(fp_rect
			(start -0.508 0.9398)
			(end 0.508 -0.9398)
			(stroke
				(width 0)
				(type default)
			)
			(fill no)
			(layer "F.CrtYd")
		)
		(fp_rect
			(start -0.508 0.9398)
			(end 0.508 -0.9398)
			(stroke
				(width 0)
				(type default)
			)
			(fill no)
			(layer "F.Fab")
		)
		(pad "1" smd custom
			(at 0 -0.4445 180)
			(size 0.1397 0.1397)
			(layers "F.Cu" "F.Mask" "F.Paste")
			(net "PE_CLK_100M_DR5_1_R_N")
			(options
				(clearance outline)
				(anchor circle)
			)
			(primitives
				(gr_poly
					(pts
						(arc
							(start -0.1778 -0.2794)
							(mid -0.249642 -0.249642)
							(end -0.2794 -0.1778)
						)
						(arc
							(start -0.2794 0.1778)
							(mid -0.249642 0.249642)
							(end -0.1778 0.2794)
						)
						(arc
							(start 0.1778 0.2794)
							(mid 0.249642 0.249642)
							(end 0.2794 0.1778)
						)
						(arc
							(start 0.2794 -0.1778)
							(mid 0.249642 -0.249642)
							(end 0.1778 -0.2794)
						)
					)
					(width 0)
					(fill yes)
				)
			)
		)
		(pad "2" smd custom
			(at 0 0.4445 180)
			(size 0.1397 0.1397)
			(layers "F.Cu" "F.Mask" "F.Paste")
			(net "PE_CLK100M_DR5_1_N")
			(options
				(clearance outline)
				(anchor circle)
			)
			(primitives
				(gr_poly
					(pts
						(arc
							(start -0.1778 -0.2794)
							(mid -0.249642 -0.249642)
							(end -0.2794 -0.1778)
						)
						(arc
							(start -0.2794 0.1778)
							(mid -0.249642 0.249642)
							(end -0.1778 0.2794)
						)
						(arc
							(start 0.1778 0.2794)
							(mid 0.249642 0.249642)
							(end 0.2794 0.1778)
						)
						(arc
							(start 0.2794 -0.1778)
							(mid 0.249642 -0.249642)
							(end 0.1778 -0.2794)
						)
					)
					(width 0)
					(fill yes)
				)
			)
		)
	)
	(footprint ""
		(layer "F.Cu")
		(at 214.757 -397.891 -90)
		(property "Reference" "U10"
			(at 0 0 270)
			(layer "F.SilkS")
			(hide yes)
			(effects
				(font
					(size 1.27 1.27)
				)
			)
		)
		(property "Value" "P2003EVG-GP"
			(at 0 -11.1252 270)
			(unlocked yes)
			(layer "F.Fab")
			(hide yes)
			(effects
				(font
					(size 1.016 1.016)
					(thickness 0.1524)
				)
			)
		)
		(property "Device Type" "SOIC8H79"
			(at 0 -12.6492 270)
			(unlocked yes)
			(layer "F.Fab")
			(hide yes)
			(effects
				(font
					(size 1.016 1.016)
					(thickness 0.1524)
				)
			)
		)
		(duplicate_pad_numbers_are_jumpers no)
		(fp_line
			(start -2.6162 3.429)
			(end -2.6162 1.4732)
			(stroke
				(width 0.4064)
				(type default)
			)
			(layer "F.SilkS")
		)
		(fp_line
			(start -2.7432 1.4224)
			(end 2.1336 1.4224)
			(stroke
				(width 0.1524)
				(type default)
			)
			(layer "F.SilkS")
		)
		(fp_line
			(start 2.1336 1.4224)
			(end 2.1336 -1.4224)
			(stroke
				(width 0.1524)
				(type default)
			)
			(layer "F.SilkS")
		)
		(fp_line
			(start -2.2352 0)
			(end -2.7432 0.508)
			(stroke
				(width 0.1524)
				(type default)
			)
			(layer "F.SilkS")
		)
		(fp_line
			(start -2.7432 -0.508)
			(end -2.2352 0)
			(stroke
				(width 0.1524)
				(type default)
			)
			(layer "F.SilkS")
		)
		(fp_line
			(start -2.7432 -1.4224)
			(end -2.7432 1.4224)
			(stroke
				(width 0.1524)
				(type default)
			)
			(layer "F.SilkS")
		)
		(fp_line
			(start 2.1336 -1.4224)
			(end -2.7432 -1.4224)
			(stroke
				(width 0.1524)
				(type default)
			)
			(layer "F.SilkS")
		)
		(fp_poly
			(pts
				(xy 2.2098 -1.4224) (xy 2.2098 1.4224) (xy -2.2225 1.4224) (xy -2.2225 -1.4224)
			)
			(stroke
				(width 0)
				(type default)
			)
			(fill yes)
			(layer "F.SilkS")
		)
		(fp_rect
			(start -2.4511 2.9972)
			(end 2.4511 -2.9972)
			(stroke
				(width 0)
				(type default)
			)
			(fill no)
			(layer "F.CrtYd")
		)
		(fp_poly
			(pts
				(xy -2.8194 3.6322) (xy -2.8194 -3.6322) (xy 2.8194 -3.6322) (xy 2.8194 -2.2987) (xy 2.4511 -2.2987)
				(xy 2.4511 -2.9972) (xy -2.4511 -2.9972) (xy -2.4511 2.9972) (xy 2.4511 2.9972) (xy 2.4511 -2.286)
				(xy 2.8194 -2.286) (xy 2.8194 3.6322)
			)
			(stroke
				(width 0)
				(type default)
			)
			(fill no)
			(layer "F.CrtYd")
		)
		(fp_rect
			(start -2.8194 3.6322)
			(end 2.8194 -3.6322)
			(stroke
				(width 0)
				(type default)
			)
			(fill no)
			(layer "F.Fab")
		)
		(pad "1" smd rect
			(at -1.905 2.54 270)
			(size 0.635 1.651)
			(layers "F.Cu" "F.Mask" "F.Paste")
			(net "P12V")
		)
		(pad "2" smd rect
			(at -0.635 2.54 270)
			(size 0.635 1.651)
			(layers "F.Cu" "F.Mask" "F.Paste")
			(net "P12V")
		)
		(pad "3" smd rect
			(at 0.635 2.54 270)
			(size 0.635 1.651)
			(layers "F.Cu" "F.Mask" "F.Paste")
			(net "P12V")
		)
		(pad "4" smd rect
			(at 1.905 2.54 270)
			(size 0.635 1.651)
			(layers "F.Cu" "F.Mask" "F.Paste")
			(net "SW_SSD1_N")
		)
		(pad "5" smd rect
			(at 1.905 -2.54 270)
			(size 0.635 1.651)
			(layers "F.Cu" "F.Mask" "F.Paste")
			(net "P12V_SSD1")
		)
		(pad "6" smd rect
			(at 0.635 -2.54 270)
			(size 0.635 1.651)
			(layers "F.Cu" "F.Mask" "F.Paste")
			(net "P12V_SSD1")
		)
		(pad "7" smd rect
			(at -0.635 -2.54 270)
			(size 0.635 1.651)
			(layers "F.Cu" "F.Mask" "F.Paste")
			(net "P12V_SSD1")
		)
		(pad "8" smd rect
			(at -1.905 -2.54 270)
			(size 0.635 1.651)
			(layers "F.Cu" "F.Mask" "F.Paste")
			(net "P12V_SSD1")
		)
	)
)
